(kicad_pcb
	(version 20260206)
	(generator "pcbnew")
	(generator_version "10.0")
	(general
		(thickness 1.6)
		(legacy_teardrops no)
	)
	(paper "A4")
	(title_block
		(title "v1-chassis-manager — T6M_CM_d_v01_1031_1645.brd")
		(comment 1 "Open CloudServer (Microsoft) / footprints 2304-2313 of 2512")
	)
	(layers
		(0 "F.Cu" signal "TOP")
		(4 "In1.Cu" signal "GND1")
		(6 "In2.Cu" signal "IN1")
		(8 "In3.Cu" signal "VCC1")
		(10 "In4.Cu" signal "VCC2")
		(12 "In5.Cu" signal "GND2")
		(14 "In6.Cu" signal "IN2")
		(16 "In7.Cu" signal "IN3")
		(18 "In8.Cu" signal "GND3")
		(2 "B.Cu" signal "BOTTOM")
		(9 "F.Adhes" user "F.Adhesive")
		(11 "B.Adhes" user "B.Adhesive")
		(13 "F.Paste" user "Package Geometry/Pastemask Top")
		(15 "B.Paste" user "Package Geometry/Pastemask Bottom")
		(5 "F.SilkS" user "Ref Des/Silkscreen Top")
		(7 "B.SilkS" user "Ref Des/Silkscreen Bottom")
		(1 "F.Mask" user "Board Geometry/Soldermask Top")
		(3 "B.Mask" user "Board Geometry/Soldermask Bottom")
		(17 "Dwgs.User" user "User.Drawings")
		(19 "Cmts.User" user "User.Comments")
		(21 "Eco1.User" user "User.Eco1")
		(23 "Eco2.User" user "User.Eco2")
		(25 "Edge.Cuts" user "Board Geometry/Outline")
		(27 "Margin" user)
		(31 "F.CrtYd" user "Package Geometry/Place Bound Top")
		(29 "B.CrtYd" user "Package Geometry/Place Bound Bottom")
		(35 "F.Fab" user "Ref Des/Assembly Top")
		(33 "B.Fab" user "Ref Des/Assembly Bottom")
	)
	(footprint ""
		(layer "B.Cu")
		(at 149.60473 -168.612312)
		(property "Reference" "C572"
			(at 1.020572 1.1303 0)
			(unlocked yes)
			(layer "B.SilkS")
			(effects
				(font
					(size 0.7874 0.5842)
					(thickness 0.1524)
				)
				(justify left mirror)
			)
		)
		(property "Value" ""
			(at 0 0 0)
			(layer "B.Fab")
			(effects
				(font
					(size 1.27 1.27)
				)
				(justify mirror)
			)
		)
		(duplicate_pad_numbers_are_jumpers no)
		(fp_line
			(start -0.7874 -0.4064)
			(end -0.7874 0.4064)
			(stroke
				(width 0.1524)
				(type default)
			)
			(layer "B.SilkS")
		)
		(fp_line
			(start -0.7874 0.4064)
			(end 0.7874 0.4064)
			(stroke
				(width 0.1524)
				(type default)
			)
			(layer "B.SilkS")
		)
		(fp_line
			(start 0 0.381)
			(end 0 -0.381)
			(stroke
				(width 0.1524)
				(type default)
			)
			(layer "B.SilkS")
		)
		(fp_line
			(start 0.7874 -0.4064)
			(end -0.7874 -0.4064)
			(stroke
				(width 0.1524)
				(type default)
			)
			(layer "B.SilkS")
		)
		(fp_line
			(start 0.7874 0.4064)
			(end 0.7874 -0.4064)
			(stroke
				(width 0.1524)
				(type default)
			)
			(layer "B.SilkS")
		)
		(fp_poly
			(pts
				(xy 0.5334 0.254) (xy 0.635 0.254) (xy 0.635 0.2286) (xy 0.635 -0.254) (xy 0.5334 -0.254) (xy 0.5334 -0.2794)
				(xy -0.5334 -0.2794) (xy -0.5334 -0.254) (xy -0.635 -0.254) (xy -0.635 0.254) (xy -0.5334 0.254)
				(xy -0.5334 0.2794) (xy 0.508 0.2794) (xy 0.5334 0.2794)
			)
			(stroke
				(width 0)
				(type default)
			)
			(fill no)
			(layer "B.CrtYd")
		)
		(pad "1" smd rect
			(at -0.40005 0 180)
			(size 0.4572 0.508)
			(layers "B.Cu" "B.Mask" "B.Paste")
			(net "GND")
		)
		(pad "2" smd rect
			(at 0.40005 0 180)
			(size 0.4572 0.508)
			(layers "B.Cu" "B.Mask" "B.Paste")
			(net "P3V3_NODE1")
		)
	)
	(footprint ""
		(layer "B.Cu")
		(at 48.24476 -185.205624 -90)
		(property "Reference" "R843"
			(at -4.15163 -0.163068 270)
			(unlocked yes)
			(layer "B.SilkS")
			(effects
				(font
					(size 0.7874 0.5842)
					(thickness 0.1524)
				)
				(justify left mirror)
			)
		)
		(property "Value" ""
			(at 0 0 90)
			(layer "B.Fab")
			(effects
				(font
					(size 1.27 1.27)
				)
				(justify mirror)
			)
		)
		(duplicate_pad_numbers_are_jumpers no)
		(fp_line
			(start -0.7874 0.4064)
			(end 0.7874 0.4064)
			(stroke
				(width 0.1524)
				(type default)
			)
			(layer "B.SilkS")
		)
		(fp_line
			(start 0.7874 0.4064)
			(end 0.7874 -0.4064)
			(stroke
				(width 0.1524)
				(type default)
			)
			(layer "B.SilkS")
		)
		(fp_line
			(start -0.7874 -0.4064)
			(end -0.7874 0.4064)
			(stroke
				(width 0.1524)
				(type default)
			)
			(layer "B.SilkS")
		)
		(fp_line
			(start 0.7874 -0.4064)
			(end -0.7874 -0.4064)
			(stroke
				(width 0.1524)
				(type default)
			)
			(layer "B.SilkS")
		)
		(fp_poly
			(pts
				(xy 0.508 0.2794) (xy 0.508 0.2286) (xy 0.635 0.2286) (xy 0.635 -0.254) (xy 0.5334 -0.254) (xy 0.5334 -0.2794)
				(xy -0.5334 -0.2794) (xy -0.5334 -0.254) (xy -0.635 -0.254) (xy -0.635 0.254) (xy -0.5334 0.254)
				(xy -0.5334 0.2794)
			)
			(stroke
				(width 0)
				(type default)
			)
			(fill no)
			(layer "B.CrtYd")
		)
		(pad "1" smd rect
			(at -0.40005 0 90)
			(size 0.4572 0.508)
			(layers "B.Cu" "B.Mask" "B.Paste")
			(net "PSU5_DC_OK_R")
		)
		(pad "2" smd rect
			(at 0.40005 0 90)
			(size 0.4572 0.508)
			(layers "B.Cu" "B.Mask" "B.Paste")
			(net "PSU5_DC_OK_R_BUF")
		)
	)
	(footprint ""
		(layer "B.Cu")
		(at 66.1289 -92.814648 90)
		(property "Reference" "R155"
			(at -2.211324 0.99949 270)
			(unlocked yes)
			(layer "B.SilkS")
			(effects
				(font
					(size 0.7874 0.5842)
					(thickness 0.1524)
				)
				(justify left mirror)
			)
		)
		(property "Value" ""
			(at 0 0 90)
			(layer "B.Fab")
			(effects
				(font
					(size 1.27 1.27)
				)
				(justify mirror)
			)
		)
		(duplicate_pad_numbers_are_jumpers no)
		(fp_line
			(start 0.7874 -0.4064)
			(end -0.7874 -0.4064)
			(stroke
				(width 0.1524)
				(type default)
			)
			(layer "B.SilkS")
		)
		(fp_line
			(start -0.7874 -0.4064)
			(end -0.7874 0.4064)
			(stroke
				(width 0.1524)
				(type default)
			)
			(layer "B.SilkS")
		)
		(fp_line
			(start 0.7874 0.4064)
			(end 0.7874 -0.4064)
			(stroke
				(width 0.1524)
				(type default)
			)
			(layer "B.SilkS")
		)
		(fp_line
			(start -0.7874 0.4064)
			(end 0.7874 0.4064)
			(stroke
				(width 0.1524)
				(type default)
			)
			(layer "B.SilkS")
		)
		(fp_poly
			(pts
				(xy 0.508 0.2794) (xy 0.508 0.2286) (xy 0.635 0.2286) (xy 0.635 -0.254) (xy 0.5334 -0.254) (xy 0.5334 -0.2794)
				(xy -0.5334 -0.2794) (xy -0.5334 -0.254) (xy -0.635 -0.254) (xy -0.635 0.254) (xy -0.5334 0.254)
				(xy -0.5334 0.2794)
			)
			(stroke
				(width 0)
				(type default)
			)
			(fill no)
			(layer "B.CrtYd")
		)
		(pad "1" smd rect
			(at -0.40005 0 270)
			(size 0.4572 0.508)
			(layers "B.Cu" "B.Mask" "B.Paste")
			(net "GND")
		)
		(pad "2" smd rect
			(at 0.40005 0 270)
			(size 0.4572 0.508)
			(layers "B.Cu" "B.Mask" "B.Paste")
			(net "PD_CPU_NODE1_BRD_ID1")
		)
	)
	(footprint ""
		(layer "B.Cu")
		(at 64.182498 -96.696784 -90)
		(property "Reference" "R88"
			(at -6.314948 5.033264 270)
			(unlocked yes)
			(layer "B.SilkS")
			(effects
				(font
					(size 0.7874 0.5842)
					(thickness 0.1524)
				)
				(justify left mirror)
			)
		)
		(property "Value" ""
			(at 0 0 90)
			(layer "B.Fab")
			(effects
				(font
					(size 1.27 1.27)
				)
				(justify mirror)
			)
		)
		(duplicate_pad_numbers_are_jumpers no)
		(fp_line
			(start -0.7874 0.4064)
			(end 0.7874 0.4064)
			(stroke
				(width 0.1524)
				(type default)
			)
			(layer "B.SilkS")
		)
		(fp_line
			(start 0.7874 0.4064)
			(end 0.7874 -0.4064)
			(stroke
				(width 0.1524)
				(type default)
			)
			(layer "B.SilkS")
		)
		(fp_line
			(start -0.7874 -0.4064)
			(end -0.7874 0.4064)
			(stroke
				(width 0.1524)
				(type default)
			)
			(layer "B.SilkS")
		)
		(fp_line
			(start 0.7874 -0.4064)
			(end -0.7874 -0.4064)
			(stroke
				(width 0.1524)
				(type default)
			)
			(layer "B.SilkS")
		)
		(fp_poly
			(pts
				(xy 0.508 0.2794) (xy 0.508 0.2286) (xy 0.635 0.2286) (xy 0.635 -0.254) (xy 0.5334 -0.254) (xy 0.5334 -0.2794)
				(xy -0.5334 -0.2794) (xy -0.5334 -0.254) (xy -0.635 -0.254) (xy -0.635 0.254) (xy -0.5334 0.254)
				(xy -0.5334 0.2794)
			)
			(stroke
				(width 0)
				(type default)
			)
			(fill no)
			(layer "B.CrtYd")
		)
		(pad "1" smd rect
			(at -0.40005 0 90)
			(size 0.4572 0.508)
			(layers "B.Cu" "B.Mask" "B.Paste")
			(net "GND")
		)
		(pad "2" smd rect
			(at 0.40005 0 90)
			(size 0.4572 0.508)
			(layers "B.Cu" "B.Mask" "B.Paste")
			(net "NODE1_BIOS_MB_REV_ID0")
		)
	)
	(footprint ""
		(layer "B.Cu")
		(at 114.543078 -123.92152 -90)
		(property "Reference" "PC90"
			(at -2.466086 -0.681228 270)
			(unlocked yes)
			(layer "B.SilkS")
			(effects
				(font
					(size 0.7874 0.5842)
					(thickness 0.1524)
				)
				(justify left mirror)
			)
		)
		(property "Value" ""
			(at 0 0 90)
			(layer "B.Fab")
			(effects
				(font
					(size 1.27 1.27)
				)
				(justify mirror)
			)
		)
		(duplicate_pad_numbers_are_jumpers no)
		(fp_line
			(start -0.7874 0.4064)
			(end 0.7874 0.4064)
			(stroke
				(width 0.1524)
				(type default)
			)
			(layer "B.SilkS")
		)
		(fp_line
			(start 0.7874 0.4064)
			(end 0.7874 -0.4064)
			(stroke
				(width 0.1524)
				(type default)
			)
			(layer "B.SilkS")
		)
		(fp_line
			(start 0 0.381)
			(end 0 -0.381)
			(stroke
				(width 0.1524)
				(type default)
			)
			(layer "B.SilkS")
		)
		(fp_line
			(start -0.7874 -0.4064)
			(end -0.7874 0.4064)
			(stroke
				(width 0.1524)
				(type default)
			)
			(layer "B.SilkS")
		)
		(fp_line
			(start 0.7874 -0.4064)
			(end -0.7874 -0.4064)
			(stroke
				(width 0.1524)
				(type default)
			)
			(layer "B.SilkS")
		)
		(fp_poly
			(pts
				(xy 0.5334 0.254) (xy 0.635 0.254) (xy 0.635 0.2286) (xy 0.635 -0.254) (xy 0.5334 -0.254) (xy 0.5334 -0.2794)
				(xy -0.5334 -0.2794) (xy -0.5334 -0.254) (xy -0.635 -0.254) (xy -0.635 0.254) (xy -0.5334 0.254)
				(xy -0.5334 0.2794) (xy 0.508 0.2794) (xy 0.5334 0.2794)
			)
			(stroke
				(width 0)
				(type default)
			)
			(fill no)
			(layer "B.CrtYd")
		)
		(pad "1" smd rect
			(at -0.40005 0 90)
			(size 0.4572 0.508)
			(layers "B.Cu" "B.Mask" "B.Paste")
			(net "SW_VR_PVCCP_NODE1_VIN_FLT")
		)
		(pad "2" smd rect
			(at 0.40005 0 90)
			(size 0.4572 0.508)
			(layers "B.Cu" "B.Mask" "B.Paste")
			(net "GND")
		)
	)
	(footprint ""
		(layer "B.Cu")
		(at 37.647118 -136.400032)
		(property "Reference" "C228"
			(at -2.115312 0.07874 0)
			(unlocked yes)
			(layer "B.SilkS")
			(effects
				(font
					(size 0.7874 0.5842)
					(thickness 0.1524)
				)
				(justify left mirror)
			)
		)
		(property "Value" ""
			(at 0 0 0)
			(layer "B.Fab")
			(effects
				(font
					(size 1.27 1.27)
				)
				(justify mirror)
			)
		)
		(duplicate_pad_numbers_are_jumpers no)
		(fp_line
			(start -0.7874 -0.4064)
			(end -0.7874 0.4064)
			(stroke
				(width 0.1524)
				(type default)
			)
			(layer "B.SilkS")
		)
		(fp_line
			(start -0.7874 0.4064)
			(end 0.7874 0.4064)
			(stroke
				(width 0.1524)
				(type default)
			)
			(layer "B.SilkS")
		)
		(fp_line
			(start 0 0.381)
			(end 0 -0.381)
			(stroke
				(width 0.1524)
				(type default)
			)
			(layer "B.SilkS")
		)
		(fp_line
			(start 0.7874 -0.4064)
			(end -0.7874 -0.4064)
			(stroke
				(width 0.1524)
				(type default)
			)
			(layer "B.SilkS")
		)
		(fp_line
			(start 0.7874 0.4064)
			(end 0.7874 -0.4064)
			(stroke
				(width 0.1524)
				(type default)
			)
			(layer "B.SilkS")
		)
		(fp_poly
			(pts
				(xy 0.5334 0.254) (xy 0.635 0.254) (xy 0.635 0.2286) (xy 0.635 -0.254) (xy 0.5334 -0.254) (xy 0.5334 -0.2794)
				(xy -0.5334 -0.2794) (xy -0.5334 -0.254) (xy -0.635 -0.254) (xy -0.635 0.254) (xy -0.5334 0.254)
				(xy -0.5334 0.2794) (xy 0.508 0.2794) (xy 0.5334 0.2794)
			)
			(stroke
				(width 0)
				(type default)
			)
			(fill no)
			(layer "B.CrtYd")
		)
		(pad "1" smd rect
			(at -0.40005 0 180)
			(size 0.4572 0.508)
			(layers "B.Cu" "B.Mask" "B.Paste")
			(net "P0V75_BMC_VTTREF_NODE1")
		)
		(pad "2" smd rect
			(at 0.40005 0 180)
			(size 0.4572 0.508)
			(layers "B.Cu" "B.Mask" "B.Paste")
			(net "GND")
		)
	)
	(footprint ""
		(layer "B.Cu")
		(at 50.457862 -71.938134 90)
		(property "Reference" "R149"
			(at -32.133794 -15.404592 270)
			(unlocked yes)
			(layer "B.SilkS")
			(effects
				(font
					(size 0.7874 0.5842)
					(thickness 0.1524)
				)
				(justify left mirror)
			)
		)
		(property "Value" ""
			(at 0 0 90)
			(layer "B.Fab")
			(effects
				(font
					(size 1.27 1.27)
				)
				(justify mirror)
			)
		)
		(duplicate_pad_numbers_are_jumpers no)
		(fp_line
			(start 0.7874 -0.4064)
			(end -0.7874 -0.4064)
			(stroke
				(width 0.1524)
				(type default)
			)
			(layer "B.SilkS")
		)
		(fp_line
			(start -0.7874 -0.4064)
			(end -0.7874 0.4064)
			(stroke
				(width 0.1524)
				(type default)
			)
			(layer "B.SilkS")
		)
		(fp_line
			(start 0.7874 0.4064)
			(end 0.7874 -0.4064)
			(stroke
				(width 0.1524)
				(type default)
			)
			(layer "B.SilkS")
		)
		(fp_line
			(start -0.7874 0.4064)
			(end 0.7874 0.4064)
			(stroke
				(width 0.1524)
				(type default)
			)
			(layer "B.SilkS")
		)
		(fp_poly
			(pts
				(xy 0.508 0.2794) (xy 0.508 0.2286) (xy 0.635 0.2286) (xy 0.635 -0.254) (xy 0.5334 -0.254) (xy 0.5334 -0.2794)
				(xy -0.5334 -0.2794) (xy -0.5334 -0.254) (xy -0.635 -0.254) (xy -0.635 0.254) (xy -0.5334 0.254)
				(xy -0.5334 0.2794)
			)
			(stroke
				(width 0)
				(type default)
			)
			(fill no)
			(layer "B.CrtYd")
		)
		(pad "1" smd rect
			(at -0.40005 0 270)
			(size 0.4572 0.508)
			(layers "B.Cu" "B.Mask" "B.Paste")
			(net "P1V5_NODE1")
		)
		(pad "2" smd rect
			(at 0.40005 0 270)
			(size 0.4572 0.508)
			(layers "B.Cu" "B.Mask" "B.Paste")
			(net "P1V5_NODE1_AM21")
		)
	)
	(footprint ""
		(layer "B.Cu")
		(at 62.067186 -79.813404 90)
		(property "Reference" "C83"
			(at -32.260032 -14.407896 270)
			(unlocked yes)
			(layer "B.SilkS")
			(effects
				(font
					(size 0.7874 0.5842)
					(thickness 0.1524)
				)
				(justify left mirror)
			)
		)
		(property "Value" ""
			(at 0 0 90)
			(layer "B.Fab")
			(effects
				(font
					(size 1.27 1.27)
				)
				(justify mirror)
			)
		)
		(duplicate_pad_numbers_are_jumpers no)
		(fp_line
			(start 0.7874 -0.4064)
			(end -0.7874 -0.4064)
			(stroke
				(width 0.1524)
				(type default)
			)
			(layer "B.SilkS")
		)
		(fp_line
			(start -0.7874 -0.4064)
			(end -0.7874 0.4064)
			(stroke
				(width 0.1524)
				(type default)
			)
			(layer "B.SilkS")
		)
		(fp_line
			(start 0 0.381)
			(end 0 -0.381)
			(stroke
				(width 0.1524)
				(type default)
			)
			(layer "B.SilkS")
		)
		(fp_line
			(start 0.7874 0.4064)
			(end 0.7874 -0.4064)
			(stroke
				(width 0.1524)
				(type default)
			)
			(layer "B.SilkS")
		)
		(fp_line
			(start -0.7874 0.4064)
			(end 0.7874 0.4064)
			(stroke
				(width 0.1524)
				(type default)
			)
			(layer "B.SilkS")
		)
		(fp_poly
			(pts
				(xy 0.5334 0.254) (xy 0.635 0.254) (xy 0.635 0.2286) (xy 0.635 -0.254) (xy 0.5334 -0.254) (xy 0.5334 -0.2794)
				(xy -0.5334 -0.2794) (xy -0.5334 -0.254) (xy -0.635 -0.254) (xy -0.635 0.254) (xy -0.5334 0.254)
				(xy -0.5334 0.2794) (xy 0.508 0.2794) (xy 0.5334 0.2794)
			)
			(stroke
				(width 0)
				(type default)
			)
			(fill no)
			(layer "B.CrtYd")
		)
		(pad "1" smd rect
			(at -0.40005 0 270)
			(size 0.4572 0.508)
			(layers "B.Cu" "B.Mask" "B.Paste")
			(net "PV_VCCP_NODE1")
		)
		(pad "2" smd rect
			(at 0.40005 0 270)
			(size 0.4572 0.508)
			(layers "B.Cu" "B.Mask" "B.Paste")
			(net "GND")
		)
	)
	(footprint ""
		(layer "B.Cu")
		(at 75.299062 -165.296596 -90)
		(property "Reference" "R917"
			(at -0.476758 2.78638 270)
			(unlocked yes)
			(layer "B.SilkS")
			(effects
				(font
					(size 0.7874 0.5842)
					(thickness 0.1524)
				)
				(justify left mirror)
			)
		)
		(property "Value" ""
			(at 0 0 90)
			(layer "B.Fab")
			(effects
				(font
					(size 1.27 1.27)
				)
				(justify mirror)
			)
		)
		(duplicate_pad_numbers_are_jumpers no)
		(fp_line
			(start -0.7874 0.4064)
			(end 0.7874 0.4064)
			(stroke
				(width 0.1524)
				(type default)
			)
			(layer "B.SilkS")
		)
		(fp_line
			(start 0.7874 0.4064)
			(end 0.7874 -0.4064)
			(stroke
				(width 0.1524)
				(type default)
			)
			(layer "B.SilkS")
		)
		(fp_line
			(start -0.7874 -0.4064)
			(end -0.7874 0.4064)
			(stroke
				(width 0.1524)
				(type default)
			)
			(layer "B.SilkS")
		)
		(fp_line
			(start 0.7874 -0.4064)
			(end -0.7874 -0.4064)
			(stroke
				(width 0.1524)
				(type default)
			)
			(layer "B.SilkS")
		)
		(fp_poly
			(pts
				(xy 0.508 0.2794) (xy 0.508 0.2286) (xy 0.635 0.2286) (xy 0.635 -0.254) (xy 0.5334 -0.254) (xy 0.5334 -0.2794)
				(xy -0.5334 -0.2794) (xy -0.5334 -0.254) (xy -0.635 -0.254) (xy -0.635 0.254) (xy -0.5334 0.254)
				(xy -0.5334 0.2794)
			)
			(stroke
				(width 0)
				(type default)
			)
			(fill no)
			(layer "B.CrtYd")
		)
		(pad "1" smd rect
			(at -0.40005 0 90)
			(size 0.4572 0.508)
			(layers "B.Cu" "B.Mask" "B.Paste")
			(net "UART_T3_NODE2_TXD")
		)
		(pad "2" smd rect
			(at 0.40005 0 90)
			(size 0.4572 0.508)
			(layers "B.Cu" "B.Mask" "B.Paste")
			(net "UART_T3_NODE2_TXD_R")
		)
	)
	(footprint ""
		(layer "B.Cu")
		(at 57.898538 -79.023718 -90)
		(property "Reference" "C44"
			(at 32.112204 14.534388 270)
			(unlocked yes)
			(layer "B.SilkS")
			(effects
				(font
					(size 0.7874 0.5842)
					(thickness 0.1524)
				)
				(justify left mirror)
			)
		)
		(property "Value" ""
			(at 0 0 90)
			(layer "B.Fab")
			(effects
				(font
					(size 1.27 1.27)
				)
				(justify mirror)
			)
		)
		(duplicate_pad_numbers_are_jumpers no)
		(fp_line
			(start -0.7874 0.4064)
			(end 0.7874 0.4064)
			(stroke
				(width 0.1524)
				(type default)
			)
			(layer "B.SilkS")
		)
		(fp_line
			(start 0.7874 0.4064)
			(end 0.7874 -0.4064)
			(stroke
				(width 0.1524)
				(type default)
			)
			(layer "B.SilkS")
		)
		(fp_line
			(start 0 0.381)
			(end 0 -0.381)
			(stroke
				(width 0.1524)
				(type default)
			)
			(layer "B.SilkS")
		)
		(fp_line
			(start -0.7874 -0.4064)
			(end -0.7874 0.4064)
			(stroke
				(width 0.1524)
				(type default)
			)
			(layer "B.SilkS")
		)
		(fp_line
			(start 0.7874 -0.4064)
			(end -0.7874 -0.4064)
			(stroke
				(width 0.1524)
				(type default)
			)
			(layer "B.SilkS")
		)
		(fp_poly
			(pts
				(xy 0.5334 0.254) (xy 0.635 0.254) (xy 0.635 0.2286) (xy 0.635 -0.254) (xy 0.5334 -0.254) (xy 0.5334 -0.2794)
				(xy -0.5334 -0.2794) (xy -0.5334 -0.254) (xy -0.635 -0.254) (xy -0.635 0.254) (xy -0.5334 0.254)
				(xy -0.5334 0.2794) (xy 0.508 0.2794) (xy 0.5334 0.2794)
			)
			(stroke
				(width 0)
				(type default)
			)
			(fill no)
			(layer "B.CrtYd")
		)
		(pad "1" smd rect
			(at -0.40005 0 90)
			(size 0.4572 0.508)
			(layers "B.Cu" "B.Mask" "B.Paste")
			(net "P1V05_NODE1")
		)
		(pad "2" smd rect
			(at 0.40005 0 90)
			(size 0.4572 0.508)
			(layers "B.Cu" "B.Mask" "B.Paste")
			(net "GND")
		)
	)
)
